FILE_TYPE = CONNECTIVITY;
{Allegro Design Entry HDL 17.2-2016 S081 (4005846) 1/11/2022}
"PAGE_NUMBER" = 21;
0"NC";
1"M_L_CPU0_SA_DQ<31:0>";
2"M_L_CPU0_SB_DQ<31:0>";
3"M_L_CPU0_SA_CB<7:0>";
4"M_L_CPU0_SB_CB<7:0>";
5"M_L_CPU0_SA_DQS_DP<9:0>";
6"M_L_CPU0_SB_DQS_DP<9:0>";
7"M_L_CPU0_SA_CA<6:0>";
8"M_L_CPU0_SB_CA<6:0>";
9"M_L_CPU0_SA_DQS_DN<9:0>";
10"M_L_CPU0_SB_DQS_DN<9:0>";
11"M_L_CPU0_ALERT_N";
12"TP_M_L_CPU0_SA_TEST39L";
13"M_L_CPU0_ALERT_R_N";
14"M_L_CPU0_CLK_DP<0>";
15"M_L_CPU0_CLK_DN<0>";
16"M_L_CPU0_SA_CS_N<0>";
17"M_L_CPU0_SA_PAR";
18"M_L_CPU0_SA_RSP<0>";
19"M_L_CPU0_SA_CS_N<1>";
20"M_L_CPU0_SB_CS_N<0>";
21"M_L_CPU0_SB_CS_N<1>";
22"M_L_CPU0_SB_RSP<0>";
23"M_L_CPU0_SB_PAR";
24"M_L_CPU0_RESET_N";
25"M_L_CPU0_SA_CA<1>";
26"M_L_CPU0_SB_CA<0>";
27"M_L_CPU0_SA_CA<0>";
28"M_L_CPU0_SB_CA<6>";
29"M_L_CPU0_SA_CA<6>";
30"M_L_CPU0_SB_CA<5>";
31"M_L_CPU0_SA_CA<5>";
32"M_L_CPU0_SB_CA<4>";
33"M_L_CPU0_SA_CA<4>";
34"M_L_CPU0_SB_CA<3>";
35"M_L_CPU0_SA_CA<3>";
36"M_L_CPU0_SB_CA<2>";
37"M_L_CPU0_SA_CA<2>";
38"M_L_CPU0_SB_CA<1>";
39"M_L_CPU0_SB_DQS_DN<9>";
40"M_L_CPU0_SB_DQS_DP<9>";
41"M_L_CPU0_SB_DQS_DN<8>";
42"M_L_CPU0_SB_DQS_DN<7>";
43"M_L_CPU0_SB_DQS_DN<6>";
44"M_L_CPU0_SB_DQS_DN<5>";
45"M_L_CPU0_SB_DQS_DN<4>";
46"M_L_CPU0_SA_DQS_DN<9>";
47"M_L_CPU0_SB_DQS_DN<3>";
48"M_L_CPU0_SB_DQS_DN<2>";
49"M_L_CPU0_SB_DQS_DN<1>";
50"M_L_CPU0_SB_DQS_DN<0>";
51"M_L_CPU0_SB_DQS_DP<4>";
52"M_L_CPU0_SB_DQS_DP<8>";
53"M_L_CPU0_SB_DQS_DP<7>";
54"M_L_CPU0_SB_DQS_DP<6>";
55"M_L_CPU0_SB_DQS_DP<5>";
56"M_L_CPU0_SA_DQS_DP<9>";
57"M_L_CPU0_SB_DQS_DP<3>";
58"M_L_CPU0_SB_DQS_DP<2>";
59"M_L_CPU0_SB_DQS_DP<1>";
60"M_L_CPU0_SB_DQS_DP<0>";
61"M_L_CPU0_SA_DQS_DN<8>";
62"M_L_CPU0_SA_DQS_DN<7>";
63"M_L_CPU0_SA_DQS_DN<6>";
64"M_L_CPU0_SA_DQS_DN<5>";
65"M_L_CPU0_SA_DQS_DN<4>";
66"M_L_CPU0_SA_DQS_DN<3>";
67"M_L_CPU0_SA_DQS_DN<2>";
68"M_L_CPU0_SA_DQS_DN<1>";
69"M_L_CPU0_SA_DQS_DN<0>";
70"M_L_CPU0_SA_DQS_DP<8>";
71"M_L_CPU0_SA_DQS_DP<7>";
72"M_L_CPU0_SA_DQS_DP<6>";
73"M_L_CPU0_SA_DQS_DP<5>";
74"M_L_CPU0_SA_DQS_DP<4>";
75"M_L_CPU0_SA_DQS_DP<3>";
76"M_L_CPU0_SA_DQS_DP<2>";
77"M_L_CPU0_SA_DQS_DP<1>";
78"M_L_CPU0_SA_DQS_DP<0>";
79"M_L_CPU0_SB_CB<7>";
80"M_L_CPU0_SB_CB<6>";
81"M_L_CPU0_SB_CB<5>";
82"M_L_CPU0_SB_CB<4>";
83"M_L_CPU0_SB_CB<3>";
84"M_L_CPU0_SB_CB<2>";
85"M_L_CPU0_SB_CB<1>";
86"M_L_CPU0_SB_CB<0>";
87"M_L_CPU0_SA_CB<1>";
88"M_L_CPU0_SA_CB<0>";
89"M_L_CPU0_SB_DQ<29>";
90"M_L_CPU0_SB_DQ<28>";
91"M_L_CPU0_SB_DQ<27>";
92"M_L_CPU0_SB_DQ<26>";
93"M_L_CPU0_SB_DQ<25>";
94"M_L_CPU0_SB_DQ<24>";
95"M_L_CPU0_SB_DQ<23>";
96"M_L_CPU0_SB_DQ<22>";
97"M_L_CPU0_SA_CB<7>";
98"M_L_CPU0_SB_DQ<21>";
99"M_L_CPU0_SA_CB<6>";
100"M_L_CPU0_SB_DQ<31>";
101"M_L_CPU0_SA_CB<5>";
102"M_L_CPU0_SB_DQ<30>";
103"M_L_CPU0_SA_CB<4>";
104"M_L_CPU0_SA_CB<3>";
105"M_L_CPU0_SA_CB<2>";
106"M_L_CPU0_SB_DQ<3>";
107"M_L_CPU0_SB_DQ<19>";
108"M_L_CPU0_SB_DQ<18>";
109"M_L_CPU0_SB_DQ<17>";
110"M_L_CPU0_SB_DQ<16>";
111"M_L_CPU0_SB_DQ<15>";
112"M_L_CPU0_SB_DQ<14>";
113"M_L_CPU0_SB_DQ<13>";
114"M_L_CPU0_SB_DQ<12>";
115"M_L_CPU0_SB_DQ<11>";
116"M_L_CPU0_SB_DQ<9>";
117"M_L_CPU0_SB_DQ<10>";
118"M_L_CPU0_SB_DQ<8>";
119"M_L_CPU0_SB_DQ<20>";
120"M_L_CPU0_SB_DQ<7>";
121"M_L_CPU0_SB_DQ<6>";
122"M_L_CPU0_SB_DQ<5>";
123"M_L_CPU0_SB_DQ<4>";
124"M_L_CPU0_SA_DQ<21>";
125"M_L_CPU0_SA_DQ<20>";
126"M_L_CPU0_SA_DQ<31>";
127"M_L_CPU0_SB_DQ<2>";
128"M_L_CPU0_SA_DQ<30>";
129"M_L_CPU0_SB_DQ<1>";
130"M_L_CPU0_SB_DQ<0>";
131"M_L_CPU0_SA_DQ<19>";
132"M_L_CPU0_SA_DQ<18>";
133"M_L_CPU0_SA_DQ<29>";
134"M_L_CPU0_SA_DQ<17>";
135"M_L_CPU0_SA_DQ<28>";
136"M_L_CPU0_SA_DQ<16>";
137"M_L_CPU0_SA_DQ<27>";
138"M_L_CPU0_SA_DQ<26>";
139"M_L_CPU0_SA_DQ<25>";
140"M_L_CPU0_SA_DQ<24>";
141"M_L_CPU0_SA_DQ<23>";
142"M_L_CPU0_SA_DQ<22>";
143"M_L_CPU0_SA_DQ<4>";
144"M_L_CPU0_SA_DQ<10>";
145"M_L_CPU0_SA_DQ<3>";
146"M_L_CPU0_SA_DQ<2>";
147"M_L_CPU0_SA_DQ<1>";
148"M_L_CPU0_SA_DQ<0>";
149"M_L_CPU0_SA_DQ<9>";
150"M_L_CPU0_SA_DQ<15>";
151"M_L_CPU0_SA_DQ<8>";
152"M_L_CPU0_SA_DQ<14>";
153"M_L_CPU0_SA_DQ<7>";
154"M_L_CPU0_SA_DQ<13>";
155"M_L_CPU0_SA_DQ<6>";
156"M_L_CPU0_SA_DQ<12>";
157"M_L_CPU0_SA_DQ<5>";
158"M_L_CPU0_SA_DQ<11>";
%"GENOA_SP5"
"35","(-4500,3625)","0","pure_quanta","I159";
;
LOCATION"U25"
$SEC"35"
CDS_SEC"35"
PART_TYPE"SMLF"
MATERIAL"IO"
VALUE"SOCKET6096_13568-001"
PART_NUMBER"DGA^6000030"
CDS_LIB"pure_quanta"
CDS_LMAN_SYM_OUTLINE"-650,2525,650,-2525"
NEEDS_NO_SIZE"TRUE";
"TEST39L"
$PN"BF11"12;
"MLA_CA1"
$PN"AY9"25;
"MLA_CHECK1"
$PN"AK11"87;
"MLA_DATA4"
$PN"J9"143;
"MLA_DATA10"
$PN"M9"144;
"MLA_DATA21"
$PN"AB11"124;
"MLB_CA0"
$PN"BG10"26;
"MLB_DATA3"
$PN"CD11"106;
"MLB_DQS_H4"
$PN"BY11"51;
"MLB_DQS_L8"
$PN"DC10"41;
"MLA_CA0"
$PN"AW9"27;
"MLA_CHECK0"
$PN"AJ9"88;
"MLA_DATA3"
$PN"G10"145;
"MLA_DATA20"
$PN"AA9"125;
"MLA_DATA31"
$PN"AJ10"126;
"MLA_DQS_H9"
$PN"AN10"56;
"MLB_DATA2"
$PN"CC9"127;
"MLB_DQS_H3"
$PN"DB9"57;
"MLB_DQS_L7"
$PN"CU10"42;
"MLA1_CS_L1"
$PN"AW10"0;
"MLA_DATA2"
$PN"F9"146;
"MLA_DATA30"
$PN"AH9"128;
"MLA_DQS_H8"
$PN"AG10"70;
"MLB_DATA1"
$PN"CC10"129;
"MLB_DATA19"
$PN"CT11"107;
"MLB_DQS_H2"
$PN"CT9"58;
"MLB_DQS_L6"
$PN"CL10"43;
"MLA0_CS_L1"
$PN"AV11"19;
"MLA1_CS_L0"
$PN"AV9"0;
"MLA_DATA1"
$PN"F11"147;
"MLA_DQS_H7"
$PN"AA10"71;
"MLB_DATA0"
$PN"CB9"130;
"MLB_DATA18"
$PN"CR9"108;
"MLB_DATA29"
$PN"DE10"89;
"MLB_DQS_H1"
$PN"CK9"59;
"MLB_DQS_L5"
$PN"CE10"44;
"ML1_CLK_L"
$PN"BG9"0;
"MLA0_CS_L0"
$PN"AU9"16;
"MLA_DATA0"
$PN"E9"148;
"MLA_DQS_H6"
$PN"R10"72;
"MLB_DATA17"
$PN"CR10"109;
"MLB_DATA28"
$PN"DD9"90;
"MLB_DQS_H0"
$PN"CD9"60;
"MLB_DQS_L4"
$PN"BW10"45;
"MLB_PAR"
$PN"BL10"23;
"ML0_CLK_L"
$PN"BD9"15;
"MLA_DQS_H5"
$PN"J10"73;
"MLA_DQS_L9"
$PN"AM11"46;
"MLA_PAR"
$PN"BC10"17;
"MLB1_RSP_L"
$PN"BR9"0;
"MLB_CHECK7"
$PN"BV11"79;
"MLB_DATA16"
$PN"CP9"110;
"MLB_DATA27"
$PN"DB11"91;
"MLB_DQS_L3"
$PN"DC9"47;
"MLA_DQS_H4"
$PN"AL9"74;
"MLA_DQS_L8"
$PN"AF11"61;
"MLB0_RSP_L"
$PN"BP9"22;
"MLB_CHECK6"
$PN"BU9"80;
"MLB_DATA15"
$PN"CP11"111;
"MLB_DATA26"
$PN"DA9"92;
"MLB_DQS_L2"
$PN"CU9"48;
"MLA_DQS_H3"
$PN"AE9"75;
"MLA_DQS_L7"
$PN"Y11"62;
"MLB_CHECK5"
$PN"BU10"81;
"MLB_DATA14"
$PN"CN9"112;
"MLB_DATA25"
$PN"DA10"93;
"MLB_DQS_L1"
$PN"CL9"49;
"ML1_CLK_H"
$PN"BF9"0;
"MLA_DATA19"
$PN"W10"131;
"MLA_DQS_H2"
$PN"W9"76;
"MLA_DQS_L6"
$PN"P11"63;
"MLB_CHECK4"
$PN"BT9"82;
"MLB_DATA13"
$PN"CN10"113;
"MLB_DATA24"
$PN"CY9"94;
"MLB_DQS_L0"
$PN"CE9"50;
"ML0_CLK_H"
$PN"BC9"14;
"MLA_DATA18"
$PN"V9"132;
"MLA_DATA29"
$PN"AH11"133;
"MLA_DQS_H1"
$PN"N9"77;
"MLA_DQS_L5"
$PN"H11"64;
"MLB_CHECK3"
$PN"CB11"83;
"MLB_DATA12"
$PN"CM9"114;
"MLB_DATA23"
$PN"CY11"95;
"MLA_DATA17"
$PN"V11"134;
"MLA_DATA28"
$PN"AG9"135;
"MLA_DQS_H0"
$PN"G9"78;
"MLA_DQS_L4"
$PN"AM9"65;
"MLB_CHECK2"
$PN"CA9"84;
"MLB_DATA11"
$PN"CK11"115;
"MLB_DATA22"
$PN"CW9"96;
"ML_ALERT_L"
$PN"AT11"13;
"MLA1_RSP_L"
$PN"BP11"0;
"MLA_CHECK7"
$PN"AR10"97;
"MLA_DATA16"
$PN"U9"136;
"MLA_DATA27"
$PN"AE10"137;
"MLA_DQS_L3"
$PN"AF9"66;
"MLB_CA6"
$PN"BK9"28;
"MLB_CHECK1"
$PN"CA10"85;
"MLB_DATA9"
$PN"CJ10"116;
"MLB_DATA10"
$PN"CJ9"117;
"MLB_DATA21"
$PN"CW10"98;
"MLA0_RSP_L"
$PN"BN10"18;
"MLA_CA6"
$PN"BB11"29;
"MLA_CHECK6"
$PN"AP9"99;
"MLA_DATA9"
$PN"M11"149;
"MLA_DATA15"
$PN"U10"150;
"MLA_DATA26"
$PN"AD9"138;
"MLA_DQS_L2"
$PN"Y9"67;
"MLB_CA5"
$PN"BK11"30;
"MLB_CHECK0"
$PN"BY9"86;
"MLB_DATA8"
$PN"CH9"118;
"MLB_DATA20"
$PN"CV9"119;
"MLB_DATA31"
$PN"DF9"100;
"MLB_DQS_H9"
$PN"BV9"40;
"MLA_CA5"
$PN"BB9"31;
"MLA_CHECK5"
$PN"AP11"101;
"MLA_DATA8"
$PN"L9"151;
"MLA_DATA14"
$PN"T9"152;
"MLA_DATA25"
$PN"AD11"139;
"MLA_DQS_L1"
$PN"P9"68;
"MLB1_CS_L1"
$PN"BM9"0;
"MLB_CA4"
$PN"BJ10"32;
"MLB_DATA7"
$PN"CH11"120;
"MLB_DATA30"
$PN"DE9"102;
"MLB_DQS_H8"
$PN"DD11"52;
"MLA_CA4"
$PN"BA9"33;
"MLA_CHECK4"
$PN"AN9"103;
"MLA_DATA7"
$PN"L10"153;
"MLA_DATA13"
$PN"T11"154;
"MLA_DATA24"
$PN"AC9"140;
"MLA_DQS_L0"
$PN"H9"69;
"MLB0_CS_L1"
$PN"BN9"21;
"MLB1_CS_L0"
$PN"BL9"0;
"MLB_CA3"
$PN"BJ9"34;
"MLB_DATA6"
$PN"CG9"121;
"MLB_DQS_H7"
$PN"CV11"53;
"MLA_CA3"
$PN"BA10"35;
"MLA_CHECK3"
$PN"AL10"104;
"MLA_DATA6"
$PN"K9"155;
"MLA_DATA12"
$PN"R9"156;
"MLA_DATA23"
$PN"AC10"141;
"MLB0_CS_L0"
$PN"BM11"20;
"MLB_CA2"
$PN"BH9"36;
"MLB_DATA5"
$PN"CG10"122;
"MLB_DQS_H6"
$PN"CM11"54;
"ML_RESET_L"
$PN"AU10"24;
"MLA_CA2"
$PN"AY11"37;
"MLA_CHECK2"
$PN"AK9"105;
"MLA_DATA5"
$PN"K11"157;
"MLA_DATA11"
$PN"N10"158;
"MLA_DATA22"
$PN"AB9"142;
"MLB_CA1"
$PN"BH11"38;
"MLB_DATA4"
$PN"CF9"123;
"MLB_DQS_H5"
$PN"CF11"55;
"MLB_DQS_L9"
$PN"BW9"39;
%"TAP"
"1","(-3225,5950)","0","mstr_standard","I162";
;
CDS_LIB"mstr_standard"
BODY_TYPE"PLUMBING"
HDL_TAP"TRUE";
"B \NAC \NWC"1;
"S \NAC"
BN"1"147;
%"TAP"
"1","(-3225,6000)","0","mstr_standard","I163";
;
CDS_LIB"mstr_standard"
BODY_TYPE"PLUMBING"
HDL_TAP"TRUE";
"B \NAC \NWC"1;
"S \NAC"
BN"0"148;
%"TAP"
"1","(-3225,5900)","0","mstr_standard","I164";
;
CDS_LIB"mstr_standard"
BODY_TYPE"PLUMBING"
HDL_TAP"TRUE";
"B \NAC \NWC"1;
"S \NAC"
BN"2"146;
%"TAP"
"1","(-3225,5850)","0","mstr_standard","I165";
;
CDS_LIB"mstr_standard"
BODY_TYPE"PLUMBING"
HDL_TAP"TRUE";
"B \NAC \NWC"1;
"S \NAC"
BN"3"145;
%"TAP"
"1","(-3225,5800)","0","mstr_standard","I166";
;
CDS_LIB"mstr_standard"
BODY_TYPE"PLUMBING"
HDL_TAP"TRUE";
"B \NAC \NWC"1;
"S \NAC"
BN"4"143;
%"TAP"
"1","(-3225,5750)","0","mstr_standard","I167";
;
CDS_LIB"mstr_standard"
BODY_TYPE"PLUMBING"
HDL_TAP"TRUE";
"B \NAC \NWC"1;
"S \NAC"
BN"5"157;
%"TAP"
"1","(-3225,5700)","0","mstr_standard","I168";
;
CDS_LIB"mstr_standard"
BODY_TYPE"PLUMBING"
HDL_TAP"TRUE";
"B \NAC \NWC"1;
"S \NAC"
BN"6"155;
%"TAP"
"1","(-3225,5650)","0","mstr_standard","I169";
;
CDS_LIB"mstr_standard"
BODY_TYPE"PLUMBING"
HDL_TAP"TRUE";
"B \NAC \NWC"1;
"S \NAC"
BN"7"153;
%"TAP"
"1","(-3225,5450)","0","mstr_standard","I170";
;
CDS_LIB"mstr_standard"
BODY_TYPE"PLUMBING"
HDL_TAP"TRUE";
"B \NAC \NWC"1;
"S \NAC"
BN"10"144;
%"TAP"
"1","(-3225,5500)","0","mstr_standard","I171";
;
CDS_LIB"mstr_standard"
BODY_TYPE"PLUMBING"
HDL_TAP"TRUE";
"B \NAC \NWC"1;
"S \NAC"
BN"9"149;
%"TAP"
"1","(-3225,5550)","0","mstr_standard","I172";
;
CDS_LIB"mstr_standard"
BODY_TYPE"PLUMBING"
HDL_TAP"TRUE";
"B \NAC \NWC"1;
"S \NAC"
BN"8"151;
%"TAP"
"1","(-3225,5400)","0","mstr_standard","I173";
;
CDS_LIB"mstr_standard"
BODY_TYPE"PLUMBING"
HDL_TAP"TRUE";
"B \NAC \NWC"1;
"S \NAC"
BN"11"158;
%"TAP"
"1","(-3225,5300)","0","mstr_standard","I174";
;
CDS_LIB"mstr_standard"
BODY_TYPE"PLUMBING"
HDL_TAP"TRUE";
"B \NAC \NWC"1;
"S \NAC"
BN"13"154;
%"TAP"
"1","(-3225,5350)","0","mstr_standard","I175";
;
CDS_LIB"mstr_standard"
BODY_TYPE"PLUMBING"
HDL_TAP"TRUE";
"B \NAC \NWC"1;
"S \NAC"
BN"12"156;
%"TAP"
"1","(-3225,5200)","0","mstr_standard","I176";
;
CDS_LIB"mstr_standard"
BODY_TYPE"PLUMBING"
HDL_TAP"TRUE";
"B \NAC \NWC"1;
"S \NAC"
BN"15"150;
%"TAP"
"1","(-3225,5250)","0","mstr_standard","I177";
;
CDS_LIB"mstr_standard"
BODY_TYPE"PLUMBING"
HDL_TAP"TRUE";
"B \NAC \NWC"1;
"S \NAC"
BN"14"152;
%"TAP"
"1","(-3225,5100)","0","mstr_standard","I178";
;
CDS_LIB"mstr_standard"
BODY_TYPE"PLUMBING"
HDL_TAP"TRUE";
"B \NAC \NWC"1;
"S \NAC"
BN"16"136;
%"TAP"
"1","(-3225,5050)","0","mstr_standard","I179";
;
CDS_LIB"mstr_standard"
BODY_TYPE"PLUMBING"
HDL_TAP"TRUE";
"B \NAC \NWC"1;
"S \NAC"
BN"17"134;
%"TAP"
"1","(-3225,5000)","0","mstr_standard","I180";
;
CDS_LIB"mstr_standard"
BODY_TYPE"PLUMBING"
HDL_TAP"TRUE";
"B \NAC \NWC"1;
"S \NAC"
BN"18"132;
%"TAP"
"1","(-3225,4950)","0","mstr_standard","I181";
;
CDS_LIB"mstr_standard"
BODY_TYPE"PLUMBING"
HDL_TAP"TRUE";
"B \NAC \NWC"1;
"S \NAC"
BN"19"131;
%"TAP"
"1","(-3225,4900)","0","mstr_standard","I182";
;
CDS_LIB"mstr_standard"
BODY_TYPE"PLUMBING"
HDL_TAP"TRUE";
"B \NAC \NWC"1;
"S \NAC"
BN"20"125;
%"TAP"
"1","(-3225,4800)","0","mstr_standard","I183";
;
CDS_LIB"mstr_standard"
BODY_TYPE"PLUMBING"
HDL_TAP"TRUE";
"B \NAC \NWC"1;
"S \NAC"
BN"22"142;
%"TAP"
"1","(-3225,4850)","0","mstr_standard","I184";
;
CDS_LIB"mstr_standard"
BODY_TYPE"PLUMBING"
HDL_TAP"TRUE";
"B \NAC \NWC"1;
"S \NAC"
BN"21"124;
%"TAP"
"1","(-3225,4750)","0","mstr_standard","I185";
;
CDS_LIB"mstr_standard"
BODY_TYPE"PLUMBING"
HDL_TAP"TRUE";
"B \NAC \NWC"1;
"S \NAC"
BN"23"141;
%"TAP"
"1","(-3225,4650)","0","mstr_standard","I186";
;
CDS_LIB"mstr_standard"
BODY_TYPE"PLUMBING"
HDL_TAP"TRUE";
"B \NAC \NWC"1;
"S \NAC"
BN"24"140;
%"TAP"
"1","(-3225,4550)","0","mstr_standard","I187";
;
CDS_LIB"mstr_standard"
BODY_TYPE"PLUMBING"
HDL_TAP"TRUE";
"B \NAC \NWC"1;
"S \NAC"
BN"26"138;
%"TAP"
"1","(-3225,4600)","0","mstr_standard","I188";
;
CDS_LIB"mstr_standard"
BODY_TYPE"PLUMBING"
HDL_TAP"TRUE";
"B \NAC \NWC"1;
"S \NAC"
BN"25"139;
%"TAP"
"1","(-3225,4500)","0","mstr_standard","I189";
;
CDS_LIB"mstr_standard"
BODY_TYPE"PLUMBING"
HDL_TAP"TRUE";
"B \NAC \NWC"1;
"S \NAC"
BN"27"137;
%"TAP"
"1","(-3225,4450)","0","mstr_standard","I190";
;
CDS_LIB"mstr_standard"
BODY_TYPE"PLUMBING"
HDL_TAP"TRUE";
"B \NAC \NWC"1;
"S \NAC"
BN"28"135;
%"TAP"
"1","(-3225,4400)","0","mstr_standard","I191";
;
CDS_LIB"mstr_standard"
BODY_TYPE"PLUMBING"
HDL_TAP"TRUE";
"B \NAC \NWC"1;
"S \NAC"
BN"29"133;
%"TAP"
"1","(-3225,4300)","0","mstr_standard","I192";
;
CDS_LIB"mstr_standard"
BODY_TYPE"PLUMBING"
HDL_TAP"TRUE";
"B \NAC \NWC"1;
"S \NAC"
BN"31"126;
%"TAP"
"1","(-3225,4350)","0","mstr_standard","I193";
;
CDS_LIB"mstr_standard"
BODY_TYPE"PLUMBING"
HDL_TAP"TRUE";
"B \NAC \NWC"1;
"S \NAC"
BN"30"128;
%"TAP"
"1","(-3225,4150)","0","mstr_standard","I194";
;
CDS_LIB"mstr_standard"
BODY_TYPE"PLUMBING"
HDL_TAP"TRUE";
"B \NAC \NWC"2;
"S \NAC"
BN"1"129;
%"TAP"
"1","(-3225,4200)","0","mstr_standard","I195";
;
CDS_LIB"mstr_standard"
BODY_TYPE"PLUMBING"
HDL_TAP"TRUE";
"B \NAC \NWC"2;
"S \NAC"
BN"0"130;
%"TAP"
"1","(-3225,4100)","0","mstr_standard","I196";
;
CDS_LIB"mstr_standard"
BODY_TYPE"PLUMBING"
HDL_TAP"TRUE";
"B \NAC \NWC"2;
"S \NAC"
BN"2"127;
%"TAP"
"1","(-3225,4050)","0","mstr_standard","I198";
;
CDS_LIB"mstr_standard"
BODY_TYPE"PLUMBING"
HDL_TAP"TRUE";
"B \NAC \NWC"2;
"S \NAC"
BN"3"106;
%"TAP"
"1","(-3225,4000)","0","mstr_standard","I199";
;
CDS_LIB"mstr_standard"
BODY_TYPE"PLUMBING"
HDL_TAP"TRUE";
"B \NAC \NWC"2;
"S \NAC"
BN"4"123;
%"TAP"
"1","(-3225,3950)","0","mstr_standard","I200";
;
CDS_LIB"mstr_standard"
BODY_TYPE"PLUMBING"
HDL_TAP"TRUE";
"B \NAC \NWC"2;
"S \NAC"
BN"5"122;
%"TAP"
"1","(-3225,3900)","0","mstr_standard","I201";
;
CDS_LIB"mstr_standard"
BODY_TYPE"PLUMBING"
HDL_TAP"TRUE";
"B \NAC \NWC"2;
"S \NAC"
BN"6"121;
%"TAP"
"1","(-3225,3850)","0","mstr_standard","I202";
;
CDS_LIB"mstr_standard"
BODY_TYPE"PLUMBING"
HDL_TAP"TRUE";
"B \NAC \NWC"2;
"S \NAC"
BN"7"120;
%"TAP"
"1","(-3225,3650)","0","mstr_standard","I203";
;
CDS_LIB"mstr_standard"
BODY_TYPE"PLUMBING"
HDL_TAP"TRUE";
"B \NAC \NWC"2;
"S \NAC"
BN"10"117;
%"TAP"
"1","(-3225,3700)","0","mstr_standard","I204";
;
CDS_LIB"mstr_standard"
BODY_TYPE"PLUMBING"
HDL_TAP"TRUE";
"B \NAC \NWC"2;
"S \NAC"
BN"9"116;
%"TAP"
"1","(-3225,3750)","0","mstr_standard","I205";
;
CDS_LIB"mstr_standard"
BODY_TYPE"PLUMBING"
HDL_TAP"TRUE";
"B \NAC \NWC"2;
"S \NAC"
BN"8"118;
%"TAP"
"1","(-3225,3600)","0","mstr_standard","I206";
;
CDS_LIB"mstr_standard"
BODY_TYPE"PLUMBING"
HDL_TAP"TRUE";
"B \NAC \NWC"2;
"S \NAC"
BN"11"115;
%"TAP"
"1","(-3225,3550)","0","mstr_standard","I207";
;
CDS_LIB"mstr_standard"
BODY_TYPE"PLUMBING"
HDL_TAP"TRUE";
"B \NAC \NWC"2;
"S \NAC"
BN"12"114;
%"TAP"
"1","(-3225,3450)","0","mstr_standard","I208";
;
CDS_LIB"mstr_standard"
BODY_TYPE"PLUMBING"
HDL_TAP"TRUE";
"B \NAC \NWC"2;
"S \NAC"
BN"14"112;
%"TAP"
"1","(-3225,3400)","0","mstr_standard","I209";
;
CDS_LIB"mstr_standard"
BODY_TYPE"PLUMBING"
HDL_TAP"TRUE";
"B \NAC \NWC"2;
"S \NAC"
BN"15"111;
%"TAP"
"1","(-3225,3500)","0","mstr_standard","I210";
;
CDS_LIB"mstr_standard"
BODY_TYPE"PLUMBING"
HDL_TAP"TRUE";
"B \NAC \NWC"2;
"S \NAC"
BN"13"113;
%"TAP"
"1","(-3225,3300)","0","mstr_standard","I211";
;
CDS_LIB"mstr_standard"
BODY_TYPE"PLUMBING"
HDL_TAP"TRUE";
"B \NAC \NWC"2;
"S \NAC"
BN"16"110;
%"TAP"
"1","(-3225,3250)","0","mstr_standard","I212";
;
CDS_LIB"mstr_standard"
BODY_TYPE"PLUMBING"
HDL_TAP"TRUE";
"B \NAC \NWC"2;
"S \NAC"
BN"17"109;
%"TAP"
"1","(-3225,3200)","0","mstr_standard","I213";
;
CDS_LIB"mstr_standard"
BODY_TYPE"PLUMBING"
HDL_TAP"TRUE";
"B \NAC \NWC"2;
"S \NAC"
BN"18"108;
%"TAP"
"1","(-3225,3150)","0","mstr_standard","I214";
;
CDS_LIB"mstr_standard"
BODY_TYPE"PLUMBING"
HDL_TAP"TRUE";
"B \NAC \NWC"2;
"S \NAC"
BN"19"107;
%"TAP"
"1","(-3225,3100)","0","mstr_standard","I215";
;
CDS_LIB"mstr_standard"
BODY_TYPE"PLUMBING"
HDL_TAP"TRUE";
"B \NAC \NWC"2;
"S \NAC"
BN"20"119;
%"TAP"
"1","(-3225,2850)","0","mstr_standard","I216";
;
CDS_LIB"mstr_standard"
BODY_TYPE"PLUMBING"
HDL_TAP"TRUE";
"B \NAC \NWC"2;
"S \NAC"
BN"24"94;
%"TAP"
"1","(-3225,3050)","0","mstr_standard","I217";
;
CDS_LIB"mstr_standard"
BODY_TYPE"PLUMBING"
HDL_TAP"TRUE";
"B \NAC \NWC"2;
"S \NAC"
BN"21"98;
%"TAP"
"1","(-3225,3000)","0","mstr_standard","I218";
;
CDS_LIB"mstr_standard"
BODY_TYPE"PLUMBING"
HDL_TAP"TRUE";
"B \NAC \NWC"2;
"S \NAC"
BN"22"96;
%"TAP"
"1","(-3225,2950)","0","mstr_standard","I219";
;
CDS_LIB"mstr_standard"
BODY_TYPE"PLUMBING"
HDL_TAP"TRUE";
"B \NAC \NWC"2;
"S \NAC"
BN"23"95;
%"TAP"
"1","(-3225,2800)","0","mstr_standard","I220";
;
CDS_LIB"mstr_standard"
BODY_TYPE"PLUMBING"
HDL_TAP"TRUE";
"B \NAC \NWC"2;
"S \NAC"
BN"25"93;
%"TAP"
"1","(-3225,2750)","0","mstr_standard","I221";
;
CDS_LIB"mstr_standard"
BODY_TYPE"PLUMBING"
HDL_TAP"TRUE";
"B \NAC \NWC"2;
"S \NAC"
BN"26"92;
%"TAP"
"1","(-3225,2700)","0","mstr_standard","I222";
;
CDS_LIB"mstr_standard"
BODY_TYPE"PLUMBING"
HDL_TAP"TRUE";
"B \NAC \NWC"2;
"S \NAC"
BN"27"91;
%"TAP"
"1","(-3225,2650)","0","mstr_standard","I223";
;
CDS_LIB"mstr_standard"
BODY_TYPE"PLUMBING"
HDL_TAP"TRUE";
"B \NAC \NWC"2;
"S \NAC"
BN"28"90;
%"TAP"
"1","(-3225,2600)","0","mstr_standard","I224";
;
CDS_LIB"mstr_standard"
BODY_TYPE"PLUMBING"
HDL_TAP"TRUE";
"B \NAC \NWC"2;
"S \NAC"
BN"29"89;
%"TAP"
"1","(-3225,2500)","0","mstr_standard","I225";
;
CDS_LIB"mstr_standard"
BODY_TYPE"PLUMBING"
HDL_TAP"TRUE";
"B \NAC \NWC"2;
"S \NAC"
BN"31"100;
%"TAP"
"1","(-3225,2550)","0","mstr_standard","I226";
;
CDS_LIB"mstr_standard"
BODY_TYPE"PLUMBING"
HDL_TAP"TRUE";
"B \NAC \NWC"2;
"S \NAC"
BN"30"102;
%"TAP"
"1","(-3225,2400)","0","mstr_standard","I227";
;
CDS_LIB"mstr_standard"
BODY_TYPE"PLUMBING"
HDL_TAP"TRUE";
"B \NAC \NWC"3;
"S \NAC"
BN"0"88;
%"TAP"
"1","(-3225,2350)","0","mstr_standard","I228";
;
CDS_LIB"mstr_standard"
BODY_TYPE"PLUMBING"
HDL_TAP"TRUE";
"B \NAC \NWC"3;
"S \NAC"
BN"1"87;
%"TAP"
"1","(-3225,2300)","0","mstr_standard","I229";
;
CDS_LIB"mstr_standard"
BODY_TYPE"PLUMBING"
HDL_TAP"TRUE";
"B \NAC \NWC"3;
"S \NAC"
BN"2"105;
%"TAP"
"1","(-3225,2250)","0","mstr_standard","I230";
;
CDS_LIB"mstr_standard"
BODY_TYPE"PLUMBING"
HDL_TAP"TRUE";
"B \NAC \NWC"3;
"S \NAC"
BN"3"104;
%"TAP"
"1","(-3225,2200)","0","mstr_standard","I231";
;
CDS_LIB"mstr_standard"
BODY_TYPE"PLUMBING"
HDL_TAP"TRUE";
"B \NAC \NWC"3;
"S \NAC"
BN"4"103;
%"TAP"
"1","(-3225,2100)","0","mstr_standard","I232";
;
CDS_LIB"mstr_standard"
BODY_TYPE"PLUMBING"
HDL_TAP"TRUE";
"B \NAC \NWC"3;
"S \NAC"
BN"6"99;
%"TAP"
"1","(-3225,2150)","0","mstr_standard","I233";
;
CDS_LIB"mstr_standard"
BODY_TYPE"PLUMBING"
HDL_TAP"TRUE";
"B \NAC \NWC"3;
"S \NAC"
BN"5"101;
%"TAP"
"1","(-3225,2050)","0","mstr_standard","I234";
;
CDS_LIB"mstr_standard"
BODY_TYPE"PLUMBING"
HDL_TAP"TRUE";
"B \NAC \NWC"3;
"S \NAC"
BN"7"97;
%"TAP"
"1","(-3225,1850)","0","mstr_standard","I236";
;
CDS_LIB"mstr_standard"
BODY_TYPE"PLUMBING"
HDL_TAP"TRUE";
"B \NAC \NWC"4;
"S \NAC"
BN"2"84;
%"TAP"
"1","(-3225,1900)","0","mstr_standard","I237";
;
CDS_LIB"mstr_standard"
BODY_TYPE"PLUMBING"
HDL_TAP"TRUE";
"B \NAC \NWC"4;
"S \NAC"
BN"1"85;
%"TAP"
"1","(-3225,1950)","0","mstr_standard","I238";
;
CDS_LIB"mstr_standard"
BODY_TYPE"PLUMBING"
HDL_TAP"TRUE";
"B \NAC \NWC"4;
"S \NAC"
BN"0"86;
%"TAP"
"1","(-3225,1800)","0","mstr_standard","I239";
;
CDS_LIB"mstr_standard"
BODY_TYPE"PLUMBING"
HDL_TAP"TRUE";
"B \NAC \NWC"4;
"S \NAC"
BN"3"83;
%"TAP"
"1","(-3225,1750)","0","mstr_standard","I240";
;
CDS_LIB"mstr_standard"
BODY_TYPE"PLUMBING"
HDL_TAP"TRUE";
"B \NAC \NWC"4;
"S \NAC"
BN"4"82;
%"TAP"
"1","(-3225,1600)","0","mstr_standard","I241";
;
CDS_LIB"mstr_standard"
BODY_TYPE"PLUMBING"
HDL_TAP"TRUE";
"B \NAC \NWC"4;
"S \NAC"
BN"7"79;
%"TAP"
"1","(-3225,1650)","0","mstr_standard","I242";
;
CDS_LIB"mstr_standard"
BODY_TYPE"PLUMBING"
HDL_TAP"TRUE";
"B \NAC \NWC"4;
"S \NAC"
BN"6"80;
%"TAP"
"1","(-3225,1700)","0","mstr_standard","I243";
;
CDS_LIB"mstr_standard"
BODY_TYPE"PLUMBING"
HDL_TAP"TRUE";
"B \NAC \NWC"4;
"S \NAC"
BN"5"81;
%"TAP"
"1","(-5650,6000)","2","mstr_standard","I244";
;
CDS_LIB"mstr_standard"
BODY_TYPE"PLUMBING"
HDL_TAP"TRUE";
"B \NAC \NWC"5;
"S \NAC"
BN"0"78;
%"TAP"
"1","(-5650,5900)","2","mstr_standard","I245";
;
CDS_LIB"mstr_standard"
BODY_TYPE"PLUMBING"
HDL_TAP"TRUE";
"B \NAC \NWC"5;
"S \NAC"
BN"1"77;
%"TAP"
"1","(-5650,5800)","2","mstr_standard","I246";
;
CDS_LIB"mstr_standard"
BODY_TYPE"PLUMBING"
HDL_TAP"TRUE";
"B \NAC \NWC"5;
"S \NAC"
BN"2"76;
%"TAP"
"1","(-5650,5700)","2","mstr_standard","I247";
;
CDS_LIB"mstr_standard"
BODY_TYPE"PLUMBING"
HDL_TAP"TRUE";
"B \NAC \NWC"5;
"S \NAC"
BN"3"75;
%"TAP"
"1","(-5650,5600)","2","mstr_standard","I248";
;
CDS_LIB"mstr_standard"
BODY_TYPE"PLUMBING"
HDL_TAP"TRUE";
"B \NAC \NWC"5;
"S \NAC"
BN"4"74;
%"TAP"
"1","(-5650,5400)","2","mstr_standard","I249";
;
CDS_LIB"mstr_standard"
BODY_TYPE"PLUMBING"
HDL_TAP"TRUE";
"B \NAC \NWC"5;
"S \NAC"
BN"6"72;
%"TAP"
"1","(-5650,5500)","2","mstr_standard","I250";
;
CDS_LIB"mstr_standard"
BODY_TYPE"PLUMBING"
HDL_TAP"TRUE";
"B \NAC \NWC"5;
"S \NAC"
BN"5"73;
%"TAP"
"1","(-5650,5300)","2","mstr_standard","I251";
;
CDS_LIB"mstr_standard"
BODY_TYPE"PLUMBING"
HDL_TAP"TRUE";
"B \NAC \NWC"5;
"S \NAC"
BN"7"71;
%"TAP"
"1","(-5650,5200)","2","mstr_standard","I252";
;
CDS_LIB"mstr_standard"
BODY_TYPE"PLUMBING"
HDL_TAP"TRUE";
"B \NAC \NWC"5;
"S \NAC"
BN"8"70;
%"TAP"
"1","(-5850,5950)","2","mstr_standard","I253";
;
CDS_LIB"mstr_standard"
BODY_TYPE"PLUMBING"
HDL_TAP"TRUE";
"B \NAC \NWC"9;
"S \NAC"
BN"0"69;
%"TAP"
"1","(-5850,5850)","2","mstr_standard","I254";
;
CDS_LIB"mstr_standard"
BODY_TYPE"PLUMBING"
HDL_TAP"TRUE";
"B \NAC \NWC"9;
"S \NAC"
BN"1"68;
%"TAP"
"1","(-5850,5750)","2","mstr_standard","I255";
;
CDS_LIB"mstr_standard"
BODY_TYPE"PLUMBING"
HDL_TAP"TRUE";
"B \NAC \NWC"9;
"S \NAC"
BN"2"67;
%"TAP"
"1","(-5850,5650)","2","mstr_standard","I256";
;
CDS_LIB"mstr_standard"
BODY_TYPE"PLUMBING"
HDL_TAP"TRUE";
"B \NAC \NWC"9;
"S \NAC"
BN"3"66;
%"TAP"
"1","(-5850,5450)","2","mstr_standard","I257";
;
CDS_LIB"mstr_standard"
BODY_TYPE"PLUMBING"
HDL_TAP"TRUE";
"B \NAC \NWC"9;
"S \NAC"
BN"5"64;
%"TAP"
"1","(-5850,5550)","2","mstr_standard","I258";
;
CDS_LIB"mstr_standard"
BODY_TYPE"PLUMBING"
HDL_TAP"TRUE";
"B \NAC \NWC"9;
"S \NAC"
BN"4"65;
%"TAP"
"1","(-5850,5350)","2","mstr_standard","I259";
;
CDS_LIB"mstr_standard"
BODY_TYPE"PLUMBING"
HDL_TAP"TRUE";
"B \NAC \NWC"9;
"S \NAC"
BN"6"63;
%"TAP"
"1","(-5850,5250)","2","mstr_standard","I260";
;
CDS_LIB"mstr_standard"
BODY_TYPE"PLUMBING"
HDL_TAP"TRUE";
"B \NAC \NWC"9;
"S \NAC"
BN"7"62;
%"TAP"
"1","(-5850,5150)","2","mstr_standard","I261";
;
CDS_LIB"mstr_standard"
BODY_TYPE"PLUMBING"
HDL_TAP"TRUE";
"B \NAC \NWC"9;
"S \NAC"
BN"8"61;
%"TAP"
"1","(-5650,5100)","2","mstr_standard","I262";
;
CDS_LIB"mstr_standard"
BODY_TYPE"PLUMBING"
HDL_TAP"TRUE";
"B \NAC \NWC"5;
"S \NAC"
BN"9"56;
%"TAP"
"1","(-5650,4950)","2","mstr_standard","I263";
;
CDS_LIB"mstr_standard"
BODY_TYPE"PLUMBING"
HDL_TAP"TRUE";
"B \NAC \NWC"6;
"S \NAC"
BN"0"60;
%"TAP"
"1","(-5650,4850)","2","mstr_standard","I264";
;
CDS_LIB"mstr_standard"
BODY_TYPE"PLUMBING"
HDL_TAP"TRUE";
"B \NAC \NWC"6;
"S \NAC"
BN"1"59;
%"TAP"
"1","(-5650,4750)","2","mstr_standard","I265";
;
CDS_LIB"mstr_standard"
BODY_TYPE"PLUMBING"
HDL_TAP"TRUE";
"B \NAC \NWC"6;
"S \NAC"
BN"2"58;
%"TAP"
"1","(-5650,4650)","2","mstr_standard","I266";
;
CDS_LIB"mstr_standard"
BODY_TYPE"PLUMBING"
HDL_TAP"TRUE";
"B \NAC \NWC"6;
"S \NAC"
BN"3"57;
%"TAP"
"1","(-5650,4550)","2","mstr_standard","I267";
;
CDS_LIB"mstr_standard"
BODY_TYPE"PLUMBING"
HDL_TAP"TRUE";
"B \NAC \NWC"6;
"S \NAC"
BN"4"51;
%"TAP"
"1","(-5650,4450)","2","mstr_standard","I268";
;
CDS_LIB"mstr_standard"
BODY_TYPE"PLUMBING"
HDL_TAP"TRUE";
"B \NAC \NWC"6;
"S \NAC"
BN"5"55;
%"TAP"
"1","(-5650,4350)","2","mstr_standard","I269";
;
CDS_LIB"mstr_standard"
BODY_TYPE"PLUMBING"
HDL_TAP"TRUE";
"B \NAC \NWC"6;
"S \NAC"
BN"6"54;
%"TAP"
"1","(-5650,4250)","2","mstr_standard","I270";
;
CDS_LIB"mstr_standard"
BODY_TYPE"PLUMBING"
HDL_TAP"TRUE";
"B \NAC \NWC"6;
"S \NAC"
BN"7"53;
%"TAP"
"1","(-5650,4150)","2","mstr_standard","I271";
;
CDS_LIB"mstr_standard"
BODY_TYPE"PLUMBING"
HDL_TAP"TRUE";
"B \NAC \NWC"6;
"S \NAC"
BN"8"52;
%"TAP"
"1","(-5850,4900)","2","mstr_standard","I272";
;
CDS_LIB"mstr_standard"
BODY_TYPE"PLUMBING"
HDL_TAP"TRUE";
"B \NAC \NWC"10;
"S \NAC"
BN"0"50;
%"TAP"
"1","(-5850,5050)","2","mstr_standard","I273";
;
CDS_LIB"mstr_standard"
BODY_TYPE"PLUMBING"
HDL_TAP"TRUE";
"B \NAC \NWC"9;
"S \NAC"
BN"9"46;
%"TAP"
"1","(-5850,4800)","2","mstr_standard","I274";
;
CDS_LIB"mstr_standard"
BODY_TYPE"PLUMBING"
HDL_TAP"TRUE";
"B \NAC \NWC"10;
"S \NAC"
BN"1"49;
%"TAP"
"1","(-5850,4700)","2","mstr_standard","I275";
;
CDS_LIB"mstr_standard"
BODY_TYPE"PLUMBING"
HDL_TAP"TRUE";
"B \NAC \NWC"10;
"S \NAC"
BN"2"48;
%"TAP"
"1","(-5850,4600)","2","mstr_standard","I276";
;
CDS_LIB"mstr_standard"
BODY_TYPE"PLUMBING"
HDL_TAP"TRUE";
"B \NAC \NWC"10;
"S \NAC"
BN"3"47;
%"TAP"
"1","(-5850,4500)","2","mstr_standard","I277";
;
CDS_LIB"mstr_standard"
BODY_TYPE"PLUMBING"
HDL_TAP"TRUE";
"B \NAC \NWC"10;
"S \NAC"
BN"4"45;
%"TAP"
"1","(-5850,4400)","2","mstr_standard","I278";
;
CDS_LIB"mstr_standard"
BODY_TYPE"PLUMBING"
HDL_TAP"TRUE";
"B \NAC \NWC"10;
"S \NAC"
BN"5"44;
%"TAP"
"1","(-5850,4300)","2","mstr_standard","I279";
;
CDS_LIB"mstr_standard"
BODY_TYPE"PLUMBING"
HDL_TAP"TRUE";
"B \NAC \NWC"10;
"S \NAC"
BN"6"43;
%"TAP"
"1","(-5850,4200)","2","mstr_standard","I280";
;
CDS_LIB"mstr_standard"
BODY_TYPE"PLUMBING"
HDL_TAP"TRUE";
"B \NAC \NWC"10;
"S \NAC"
BN"7"42;
%"TAP"
"1","(-5850,4100)","2","mstr_standard","I281";
;
CDS_LIB"mstr_standard"
BODY_TYPE"PLUMBING"
HDL_TAP"TRUE";
"B \NAC \NWC"10;
"S \NAC"
BN"8"41;
%"TAP"
"1","(-5650,4050)","2","mstr_standard","I286";
;
CDS_LIB"mstr_standard"
BODY_TYPE"PLUMBING"
HDL_TAP"TRUE";
"B \NAC \NWC"6;
"S \NAC"
BN"9"40;
%"TAP"
"1","(-5850,4000)","2","mstr_standard","I287";
;
CDS_LIB"mstr_standard"
BODY_TYPE"PLUMBING"
HDL_TAP"TRUE";
"B \NAC \NWC"10;
"S \NAC"
BN"9"39;
%"TAP"
"1","(-5850,3850)","2","mstr_standard","I288";
;
CDS_LIB"mstr_standard"
BODY_TYPE"PLUMBING"
HDL_TAP"TRUE";
"B \NAC \NWC"7;
"S \NAC"
BN"0"27;
%"TAP"
"1","(-5850,3750)","2","mstr_standard","I289";
;
CDS_LIB"mstr_standard"
BODY_TYPE"PLUMBING"
HDL_TAP"TRUE";
"B \NAC \NWC"7;
"S \NAC"
BN"2"37;
%"TAP"
"1","(-5850,3800)","2","mstr_standard","I290";
;
CDS_LIB"mstr_standard"
BODY_TYPE"PLUMBING"
HDL_TAP"TRUE";
"B \NAC \NWC"7;
"S \NAC"
BN"1"25;
%"TAP"
"1","(-5850,3700)","2","mstr_standard","I291";
;
CDS_LIB"mstr_standard"
BODY_TYPE"PLUMBING"
HDL_TAP"TRUE";
"B \NAC \NWC"7;
"S \NAC"
BN"3"35;
%"TAP"
"1","(-5850,3650)","2","mstr_standard","I292";
;
CDS_LIB"mstr_standard"
BODY_TYPE"PLUMBING"
HDL_TAP"TRUE";
"B \NAC \NWC"7;
"S \NAC"
BN"4"33;
%"TAP"
"1","(-5850,3600)","2","mstr_standard","I293";
;
CDS_LIB"mstr_standard"
BODY_TYPE"PLUMBING"
HDL_TAP"TRUE";
"B \NAC \NWC"7;
"S \NAC"
BN"5"31;
%"TAP"
"1","(-5850,3350)","2","mstr_standard","I294";
;
CDS_LIB"mstr_standard"
BODY_TYPE"PLUMBING"
HDL_TAP"TRUE";
"B \NAC \NWC"8;
"S \NAC"
BN"2"36;
%"TAP"
"1","(-5850,3550)","2","mstr_standard","I295";
;
CDS_LIB"mstr_standard"
BODY_TYPE"PLUMBING"
HDL_TAP"TRUE";
"B \NAC \NWC"7;
"S \NAC"
BN"6"29;
%"TAP"
"1","(-5850,3450)","2","mstr_standard","I296";
;
CDS_LIB"mstr_standard"
BODY_TYPE"PLUMBING"
HDL_TAP"TRUE";
"B \NAC \NWC"8;
"S \NAC"
BN"0"26;
%"TAP"
"1","(-5850,3400)","2","mstr_standard","I297";
;
CDS_LIB"mstr_standard"
BODY_TYPE"PLUMBING"
HDL_TAP"TRUE";
"B \NAC \NWC"8;
"S \NAC"
BN"1"38;
%"TAP"
"1","(-5850,3200)","2","mstr_standard","I298";
;
CDS_LIB"mstr_standard"
BODY_TYPE"PLUMBING"
HDL_TAP"TRUE";
"B \NAC \NWC"8;
"S \NAC"
BN"5"30;
%"TAP"
"1","(-5850,3300)","2","mstr_standard","I299";
;
CDS_LIB"mstr_standard"
BODY_TYPE"PLUMBING"
HDL_TAP"TRUE";
"B \NAC \NWC"8;
"S \NAC"
BN"3"34;
%"TAP"
"1","(-5850,3250)","2","mstr_standard","I300";
;
CDS_LIB"mstr_standard"
BODY_TYPE"PLUMBING"
HDL_TAP"TRUE";
"B \NAC \NWC"8;
"S \NAC"
BN"4"32;
%"TAP"
"1","(-5850,3150)","2","mstr_standard","I301";
;
CDS_LIB"mstr_standard"
BODY_TYPE"PLUMBING"
HDL_TAP"TRUE";
"B \NAC \NWC"8;
"S \NAC"
BN"6"28;
%"Q_RES"
"1","(-6775,2150)","0","pure_quanta","I314";
;
LOCATION"R386"
$SEC"1"
CDS_SEC"1"
TOLERANCE"1%"
VALUE"15   "
PART_NUMBER"CS01502FB11"
PACK_TYPE"0402LF"
CDS_LIB"pure_quanta"
WATTAGE"1/16W"
MATERIAL"CHIP";
"B"
$PN"2"13;
"A"
$PN"1"11;
END.
